(kicad_pcb
	(version 20260206)
	(generator "pcbnew")
	(generator_version "10.0")
	(general
		(thickness 1.6)
		(legacy_teardrops no)
	)
	(paper "A4")
	(title_block
		(title "04192023_DAF0TMB3IC0_F0TG_MB_C_brd_V02_OCP.brd")
		(comment 1 "Grand Teton / footprint 4167 of 8354 (J17), pads 1-113 of 291")
	)
	(layers
		(0 "F.Cu" signal "TOP")
		(4 "In1.Cu" signal "GND")
		(6 "In2.Cu" signal "IN1")
		(8 "In3.Cu" signal "GND1")
		(10 "In4.Cu" signal "IN2")
		(12 "In5.Cu" signal "GND2")
		(14 "In6.Cu" signal "IN3")
		(16 "In7.Cu" signal "GND3")
		(18 "In8.Cu" signal "VCC")
		(20 "In9.Cu" signal "VCC1")
		(22 "In10.Cu" signal "GND4")
		(24 "In11.Cu" signal "IN4")
		(26 "In12.Cu" signal "GND5")
		(28 "In13.Cu" signal "IN5")
		(30 "In14.Cu" signal "GND6")
		(32 "In15.Cu" signal "IN6")
		(34 "In16.Cu" signal "GND7")
		(2 "B.Cu" signal "BOTTOM")
		(9 "F.Adhes" user "F.Adhesive")
		(11 "B.Adhes" user "B.Adhesive")
		(13 "F.Paste" user "Package Geometry/Pastemask Top")
		(15 "B.Paste" user "Package Geometry/Pastemask Bottom")
		(5 "F.SilkS" user "Ref Des/Silkscreen Top")
		(7 "B.SilkS" user "Ref Des/Silkscreen Bottom")
		(1 "F.Mask" user "Board Geometry/Soldermask Top")
		(3 "B.Mask" user "Board Geometry/Soldermask Bottom")
		(17 "Dwgs.User" user "User.Drawings")
		(19 "Cmts.User" user "User.Comments")
		(21 "Eco1.User" user "User.Eco1")
		(23 "Eco2.User" user "User.Eco2")
		(25 "Edge.Cuts" user "Board Geometry/Outline")
		(27 "Margin" user)
		(31 "F.CrtYd" user "Package Geometry/Place Bound Top")
		(29 "B.CrtYd" user "Package Geometry/Place Bound Bottom")
		(35 "F.Fab" user "Ref Des/Assembly Top")
		(33 "B.Fab" user "Ref Des/Assembly Bottom")
	)
	(footprint ""
		(layer "F.Cu")
		(at 290.230052 -255.560068 180)
		(property "Reference" "J17"
			(at -2.2098 -81.984088 0)
			(unlocked yes)
			(layer "F.SilkS")
			(effects
				(font
					(size 0.7874 0.5842)
					(thickness 0.1524)
				)
			)
		)
		(property "Value" ""
			(at 0 0 180)
			(layer "F.Fab")
			(effects
				(font
					(size 1.27 1.27)
				)
			)
		)
		(duplicate_pad_numbers_are_jumpers no)
		(pad "1" smd rect
			(at -2.050034 -63.324994 90)
			(size 0.519938 1.4986)
			(layers "F.Cu" "F.Mask" "F.Paste")
			(net "P12V_MEM_CPU0")
		)
		(pad "2" smd rect
			(at -2.050034 -62.47511 90)
			(size 0.519938 1.4986)
			(layers "F.Cu" "F.Mask" "F.Paste")
			(net "Net_2277")
		)
		(pad "3" smd rect
			(at -2.050034 -61.624972 90)
			(size 0.519938 1.4986)
			(layers "F.Cu" "F.Mask" "F.Paste")
			(net "P3V3_AUX")
		)
		(pad "4" smd rect
			(at -2.050034 -60.775088 90)
			(size 0.519938 1.4986)
			(layers "F.Cu" "F.Mask" "F.Paste")
			(net "I3C_SPD_DDRC_CPU0_SCL")
		)
		(pad "5" smd rect
			(at -2.050034 -59.92495 90)
			(size 0.519938 1.4986)
			(layers "F.Cu" "F.Mask" "F.Paste")
			(net "I3C_SPD_DDRC_CPU0_SDA")
		)
		(pad "6" smd rect
			(at -2.050034 -59.075066 90)
			(size 0.519938 1.4986)
			(layers "F.Cu" "F.Mask" "F.Paste")
			(net "GND")
		)
		(pad "7" smd rect
			(at -2.050034 -58.224928 90)
			(size 0.519938 1.4986)
			(layers "F.Cu" "F.Mask" "F.Paste")
			(net "M_C_CPU0_SA_DQ<0>")
		)
		(pad "8" smd rect
			(at -2.050034 -57.375044 90)
			(size 0.519938 1.4986)
			(layers "F.Cu" "F.Mask" "F.Paste")
			(net "GND")
		)
		(pad "9" smd rect
			(at -2.050034 -56.524906 90)
			(size 0.519938 1.4986)
			(layers "F.Cu" "F.Mask" "F.Paste")
			(net "M_C_CPU0_SA_DQ<1>")
		)
		(pad "10" smd rect
			(at -2.050034 -55.675022 90)
			(size 0.519938 1.4986)
			(layers "F.Cu" "F.Mask" "F.Paste")
			(net "GND")
		)
		(pad "11" smd rect
			(at -2.050034 -54.824884 90)
			(size 0.519938 1.4986)
			(layers "F.Cu" "F.Mask" "F.Paste")
			(net "M_C_CPU0_SA_DQS_DP<0>")
		)
		(pad "12" smd rect
			(at -2.050034 -53.975 90)
			(size 0.519938 1.4986)
			(layers "F.Cu" "F.Mask" "F.Paste")
			(net "M_C_CPU0_SA_DQS_DN<0>")
		)
		(pad "13" smd rect
			(at -2.050034 -53.125116 90)
			(size 0.519938 1.4986)
			(layers "F.Cu" "F.Mask" "F.Paste")
			(net "GND")
		)
		(pad "14" smd rect
			(at -2.050034 -52.274978 90)
			(size 0.519938 1.4986)
			(layers "F.Cu" "F.Mask" "F.Paste")
			(net "M_C_CPU0_SA_DQ<4>")
		)
		(pad "15" smd rect
			(at -2.050034 -51.425094 90)
			(size 0.519938 1.4986)
			(layers "F.Cu" "F.Mask" "F.Paste")
			(net "GND")
		)
		(pad "16" smd rect
			(at -2.050034 -50.574956 90)
			(size 0.519938 1.4986)
			(layers "F.Cu" "F.Mask" "F.Paste")
			(net "M_C_CPU0_SA_DQ<5>")
		)
		(pad "17" smd rect
			(at -2.050034 -49.725072 90)
			(size 0.519938 1.4986)
			(layers "F.Cu" "F.Mask" "F.Paste")
			(net "GND")
		)
		(pad "18" smd rect
			(at -2.050034 -48.874934 90)
			(size 0.519938 1.4986)
			(layers "F.Cu" "F.Mask" "F.Paste")
			(net "M_C_CPU0_SA_DQ<8>")
		)
		(pad "19" smd rect
			(at -2.050034 -48.02505 90)
			(size 0.519938 1.4986)
			(layers "F.Cu" "F.Mask" "F.Paste")
			(net "GND")
		)
		(pad "20" smd rect
			(at -2.050034 -47.174912 90)
			(size 0.519938 1.4986)
			(layers "F.Cu" "F.Mask" "F.Paste")
			(net "M_C_CPU0_SA_DQ<9>")
		)
		(pad "21" smd rect
			(at -2.050034 -46.325028 90)
			(size 0.519938 1.4986)
			(layers "F.Cu" "F.Mask" "F.Paste")
			(net "GND")
		)
		(pad "22" smd rect
			(at -2.050034 -45.47489 90)
			(size 0.519938 1.4986)
			(layers "F.Cu" "F.Mask" "F.Paste")
			(net "M_C_CPU0_SA_DQS_DP<1>")
		)
		(pad "23" smd rect
			(at -2.050034 -44.625006 90)
			(size 0.519938 1.4986)
			(layers "F.Cu" "F.Mask" "F.Paste")
			(net "M_C_CPU0_SA_DQS_DN<1>")
		)
		(pad "24" smd rect
			(at -2.050034 -43.775122 90)
			(size 0.519938 1.4986)
			(layers "F.Cu" "F.Mask" "F.Paste")
			(net "GND")
		)
		(pad "25" smd rect
			(at -2.050034 -42.924984 90)
			(size 0.519938 1.4986)
			(layers "F.Cu" "F.Mask" "F.Paste")
			(net "M_C_CPU0_SA_DQ<12>")
		)
		(pad "26" smd rect
			(at -2.050034 -42.0751 90)
			(size 0.519938 1.4986)
			(layers "F.Cu" "F.Mask" "F.Paste")
			(net "GND")
		)
		(pad "27" smd rect
			(at -2.050034 -41.224962 90)
			(size 0.519938 1.4986)
			(layers "F.Cu" "F.Mask" "F.Paste")
			(net "M_C_CPU0_SA_DQ<13>")
		)
		(pad "28" smd rect
			(at -2.050034 -40.375078 90)
			(size 0.519938 1.4986)
			(layers "F.Cu" "F.Mask" "F.Paste")
			(net "GND")
		)
		(pad "29" smd rect
			(at -2.050034 -39.52494 90)
			(size 0.519938 1.4986)
			(layers "F.Cu" "F.Mask" "F.Paste")
			(net "M_C_CPU0_SA_DQ<16>")
		)
		(pad "30" smd rect
			(at -2.050034 -38.675056 90)
			(size 0.519938 1.4986)
			(layers "F.Cu" "F.Mask" "F.Paste")
			(net "GND")
		)
		(pad "31" smd rect
			(at -2.050034 -37.824918 90)
			(size 0.519938 1.4986)
			(layers "F.Cu" "F.Mask" "F.Paste")
			(net "M_C_CPU0_SA_DQ<17>")
		)
		(pad "32" smd rect
			(at -2.050034 -36.975034 90)
			(size 0.519938 1.4986)
			(layers "F.Cu" "F.Mask" "F.Paste")
			(net "GND")
		)
		(pad "33" smd rect
			(at -2.050034 -36.124896 90)
			(size 0.519938 1.4986)
			(layers "F.Cu" "F.Mask" "F.Paste")
			(net "M_C_CPU0_SA_DQS_DP<2>")
		)
		(pad "34" smd rect
			(at -2.050034 -35.275012 90)
			(size 0.519938 1.4986)
			(layers "F.Cu" "F.Mask" "F.Paste")
			(net "M_C_CPU0_SA_DQS_DN<2>")
		)
		(pad "35" smd rect
			(at -2.050034 -34.425128 90)
			(size 0.519938 1.4986)
			(layers "F.Cu" "F.Mask" "F.Paste")
			(net "GND")
		)
		(pad "36" smd rect
			(at -2.050034 -33.57499 90)
			(size 0.519938 1.4986)
			(layers "F.Cu" "F.Mask" "F.Paste")
			(net "M_C_CPU0_SA_DQ<20>")
		)
		(pad "37" smd rect
			(at -2.050034 -32.725106 90)
			(size 0.519938 1.4986)
			(layers "F.Cu" "F.Mask" "F.Paste")
			(net "GND")
		)
		(pad "38" smd rect
			(at -2.050034 -31.874968 90)
			(size 0.519938 1.4986)
			(layers "F.Cu" "F.Mask" "F.Paste")
			(net "M_C_CPU0_SA_DQ<21>")
		)
		(pad "39" smd rect
			(at -2.050034 -31.025084 90)
			(size 0.519938 1.4986)
			(layers "F.Cu" "F.Mask" "F.Paste")
			(net "GND")
		)
		(pad "40" smd rect
			(at -2.050034 -30.174946 90)
			(size 0.519938 1.4986)
			(layers "F.Cu" "F.Mask" "F.Paste")
			(net "M_C_CPU0_SA_DQ<24>")
		)
		(pad "41" smd rect
			(at -2.050034 -29.325062 90)
			(size 0.519938 1.4986)
			(layers "F.Cu" "F.Mask" "F.Paste")
			(net "GND")
		)
		(pad "42" smd rect
			(at -2.050034 -28.474924 90)
			(size 0.519938 1.4986)
			(layers "F.Cu" "F.Mask" "F.Paste")
			(net "M_C_CPU0_SA_DQ<25>")
		)
		(pad "43" smd rect
			(at -2.050034 -27.62504 90)
			(size 0.519938 1.4986)
			(layers "F.Cu" "F.Mask" "F.Paste")
			(net "GND")
		)
		(pad "44" smd rect
			(at -2.050034 -26.774902 90)
			(size 0.519938 1.4986)
			(layers "F.Cu" "F.Mask" "F.Paste")
			(net "M_C_CPU0_SA_DQS_DP<3>")
		)
		(pad "45" smd rect
			(at -2.050034 -25.925018 90)
			(size 0.519938 1.4986)
			(layers "F.Cu" "F.Mask" "F.Paste")
			(net "M_C_CPU0_SA_DQS_DN<3>")
		)
		(pad "46" smd rect
			(at -2.050034 -25.07488 90)
			(size 0.519938 1.4986)
			(layers "F.Cu" "F.Mask" "F.Paste")
			(net "GND")
		)
		(pad "47" smd rect
			(at -2.050034 -24.224996 90)
			(size 0.519938 1.4986)
			(layers "F.Cu" "F.Mask" "F.Paste")
			(net "M_C_CPU0_SA_DQ<28>")
		)
		(pad "48" smd rect
			(at -2.050034 -23.375112 90)
			(size 0.519938 1.4986)
			(layers "F.Cu" "F.Mask" "F.Paste")
			(net "GND")
		)
		(pad "49" smd rect
			(at -2.050034 -22.524974 90)
			(size 0.519938 1.4986)
			(layers "F.Cu" "F.Mask" "F.Paste")
			(net "M_C_CPU0_SA_DQ<29>")
		)
		(pad "50" smd rect
			(at -2.050034 -21.67509 90)
			(size 0.519938 1.4986)
			(layers "F.Cu" "F.Mask" "F.Paste")
			(net "GND")
		)
		(pad "51" smd rect
			(at -2.050034 -20.824952 90)
			(size 0.519938 1.4986)
			(layers "F.Cu" "F.Mask" "F.Paste")
			(net "M_C_CPU0_SA_CB<0>")
		)
		(pad "52" smd rect
			(at -2.050034 -19.975068 90)
			(size 0.519938 1.4986)
			(layers "F.Cu" "F.Mask" "F.Paste")
			(net "GND")
		)
		(pad "53" smd rect
			(at -2.050034 -19.12493 90)
			(size 0.519938 1.4986)
			(layers "F.Cu" "F.Mask" "F.Paste")
			(net "M_C_CPU0_SA_CB<1>")
		)
		(pad "54" smd rect
			(at -2.050034 -18.275046 90)
			(size 0.519938 1.4986)
			(layers "F.Cu" "F.Mask" "F.Paste")
			(net "GND")
		)
		(pad "55" smd rect
			(at -2.050034 -17.424908 90)
			(size 0.519938 1.4986)
			(layers "F.Cu" "F.Mask" "F.Paste")
			(net "M_C_CPU0_SA_DQS_DP<4>")
		)
		(pad "56" smd rect
			(at -2.050034 -16.575024 90)
			(size 0.519938 1.4986)
			(layers "F.Cu" "F.Mask" "F.Paste")
			(net "M_C_CPU0_SA_DQS_DN<4>")
		)
		(pad "57" smd rect
			(at -2.050034 -15.724886 90)
			(size 0.519938 1.4986)
			(layers "F.Cu" "F.Mask" "F.Paste")
			(net "GND")
		)
		(pad "58" smd rect
			(at -2.050034 -14.875002 90)
			(size 0.519938 1.4986)
			(layers "F.Cu" "F.Mask" "F.Paste")
			(net "M_C_CPU0_SA_CB<4>")
		)
		(pad "59" smd rect
			(at -2.050034 -14.025118 90)
			(size 0.519938 1.4986)
			(layers "F.Cu" "F.Mask" "F.Paste")
			(net "GND")
		)
		(pad "60" smd rect
			(at -2.050034 -13.17498 90)
			(size 0.519938 1.4986)
			(layers "F.Cu" "F.Mask" "F.Paste")
			(net "M_C_CPU0_SA_CB<5>")
		)
		(pad "61" smd rect
			(at -2.050034 -12.325096 90)
			(size 0.519938 1.4986)
			(layers "F.Cu" "F.Mask" "F.Paste")
			(net "GND")
		)
		(pad "62" smd rect
			(at -2.050034 -11.474958 90)
			(size 0.519938 1.4986)
			(layers "F.Cu" "F.Mask" "F.Paste")
			(net "M_C_CPU0_ALERT_N")
		)
		(pad "63" smd rect
			(at -2.050034 -10.625074 90)
			(size 0.519938 1.4986)
			(layers "F.Cu" "F.Mask" "F.Paste")
			(net "GND")
		)
		(pad "64" smd rect
			(at -2.050034 -9.774936 90)
			(size 0.519938 1.4986)
			(layers "F.Cu" "F.Mask" "F.Paste")
			(net "M_C_CPU0_SA_CS_N<0>")
		)
		(pad "65" smd rect
			(at -2.050034 -8.925052 90)
			(size 0.519938 1.4986)
			(layers "F.Cu" "F.Mask" "F.Paste")
			(net "GND")
		)
		(pad "66" smd rect
			(at -2.050034 -8.074914 90)
			(size 0.519938 1.4986)
			(layers "F.Cu" "F.Mask" "F.Paste")
			(net "M_C_CPU0_SA_CA<0>")
		)
		(pad "67" smd rect
			(at -2.050034 -7.22503 90)
			(size 0.519938 1.4986)
			(layers "F.Cu" "F.Mask" "F.Paste")
			(net "GND")
		)
		(pad "68" smd rect
			(at -2.050034 -6.374892 90)
			(size 0.519938 1.4986)
			(layers "F.Cu" "F.Mask" "F.Paste")
			(net "M_C_CPU0_SA_CA<2>")
		)
		(pad "69" smd rect
			(at -2.050034 -5.525008 90)
			(size 0.519938 1.4986)
			(layers "F.Cu" "F.Mask" "F.Paste")
			(net "GND")
		)
		(pad "70" smd rect
			(at -2.050034 -4.675124 90)
			(size 0.519938 1.4986)
			(layers "F.Cu" "F.Mask" "F.Paste")
			(net "M_C_CPU0_SA_CA<4>")
		)
		(pad "71" smd rect
			(at -2.050034 -3.824986 90)
			(size 0.519938 1.4986)
			(layers "F.Cu" "F.Mask" "F.Paste")
			(net "GND")
		)
		(pad "72" smd rect
			(at -2.050034 -2.975102 90)
			(size 0.519938 1.4986)
			(layers "F.Cu" "F.Mask" "F.Paste")
			(net "M_C_CPU0_SA_CA<6>")
		)
		(pad "73" smd rect
			(at -2.050034 -2.124964 90)
			(size 0.519938 1.4986)
			(layers "F.Cu" "F.Mask" "F.Paste")
			(net "GND")
		)
		(pad "74" smd rect
			(at -2.050034 -1.27508 90)
			(size 0.519938 1.4986)
			(layers "F.Cu" "F.Mask" "F.Paste")
			(net "M_C_CPU0_SA_PAR")
		)
		(pad "75" smd rect
			(at -2.050034 -0.424942 90)
			(size 0.519938 1.4986)
			(layers "F.Cu" "F.Mask" "F.Paste")
			(net "GND")
		)
		(pad "76" smd rect
			(at -2.050034 5.525008 90)
			(size 0.519938 1.4986)
			(layers "F.Cu" "F.Mask" "F.Paste")
			(net "M_C_CPU0_SB_CA<0>")
		)
		(pad "77" smd rect
			(at -2.050034 6.374892 90)
			(size 0.519938 1.4986)
			(layers "F.Cu" "F.Mask" "F.Paste")
			(net "GND")
		)
		(pad "78" smd rect
			(at -2.050034 7.22503 90)
			(size 0.519938 1.4986)
			(layers "F.Cu" "F.Mask" "F.Paste")
			(net "M_C_CPU0_SB_CA<2>")
		)
		(pad "79" smd rect
			(at -2.050034 8.074914 90)
			(size 0.519938 1.4986)
			(layers "F.Cu" "F.Mask" "F.Paste")
			(net "GND")
		)
		(pad "80" smd rect
			(at -2.050034 8.925052 90)
			(size 0.519938 1.4986)
			(layers "F.Cu" "F.Mask" "F.Paste")
			(net "M_C_CPU0_SB_CA<4>")
		)
		(pad "81" smd rect
			(at -2.050034 9.774936 90)
			(size 0.519938 1.4986)
			(layers "F.Cu" "F.Mask" "F.Paste")
			(net "GND")
		)
		(pad "82" smd rect
			(at -2.050034 10.625074 90)
			(size 0.519938 1.4986)
			(layers "F.Cu" "F.Mask" "F.Paste")
			(net "M_C_CPU0_SB_CA<6>")
		)
		(pad "83" smd rect
			(at -2.050034 11.474958 90)
			(size 0.519938 1.4986)
			(layers "F.Cu" "F.Mask" "F.Paste")
			(net "GND")
		)
		(pad "84" smd rect
			(at -2.050034 12.325096 90)
			(size 0.519938 1.4986)
			(layers "F.Cu" "F.Mask" "F.Paste")
			(net "M_C_CPU0_SB_CS_N<0>")
		)
		(pad "85" smd rect
			(at -2.050034 13.17498 90)
			(size 0.519938 1.4986)
			(layers "F.Cu" "F.Mask" "F.Paste")
			(net "GND")
		)
		(pad "86" smd rect
			(at -2.050034 14.025118 90)
			(size 0.519938 1.4986)
			(layers "F.Cu" "F.Mask" "F.Paste")
			(net "M_C_CPU0_SA_RSP<0>")
		)
		(pad "87" smd rect
			(at -2.050034 14.875002 90)
			(size 0.519938 1.4986)
			(layers "F.Cu" "F.Mask" "F.Paste")
			(net "M_C_CPU0_SB_RSP<0>")
		)
		(pad "88" smd rect
			(at -2.050034 15.724886 90)
			(size 0.519938 1.4986)
			(layers "F.Cu" "F.Mask" "F.Paste")
			(net "GND")
		)
		(pad "89" smd rect
			(at -2.050034 16.575024 90)
			(size 0.519938 1.4986)
			(layers "F.Cu" "F.Mask" "F.Paste")
			(net "M_C_CPU0_SB_CB<4>")
		)
		(pad "90" smd rect
			(at -2.050034 17.424908 90)
			(size 0.519938 1.4986)
			(layers "F.Cu" "F.Mask" "F.Paste")
			(net "GND")
		)
		(pad "91" smd rect
			(at -2.050034 18.275046 90)
			(size 0.519938 1.4986)
			(layers "F.Cu" "F.Mask" "F.Paste")
			(net "M_C_CPU0_SB_CB<5>")
		)
		(pad "92" smd rect
			(at -2.050034 19.12493 90)
			(size 0.519938 1.4986)
			(layers "F.Cu" "F.Mask" "F.Paste")
			(net "GND")
		)
		(pad "93" smd rect
			(at -2.050034 19.975068 90)
			(size 0.519938 1.4986)
			(layers "F.Cu" "F.Mask" "F.Paste")
			(net "M_C_CPU0_SB_DQS_DP<9>")
		)
		(pad "94" smd rect
			(at -2.050034 20.824952 90)
			(size 0.519938 1.4986)
			(layers "F.Cu" "F.Mask" "F.Paste")
			(net "M_C_CPU0_SB_DQS_DN<9>")
		)
		(pad "95" smd rect
			(at -2.050034 21.67509 90)
			(size 0.519938 1.4986)
			(layers "F.Cu" "F.Mask" "F.Paste")
			(net "GND")
		)
		(pad "96" smd rect
			(at -2.050034 22.524974 90)
			(size 0.519938 1.4986)
			(layers "F.Cu" "F.Mask" "F.Paste")
			(net "M_C_CPU0_SB_CB<0>")
		)
		(pad "97" smd rect
			(at -2.050034 23.375112 90)
			(size 0.519938 1.4986)
			(layers "F.Cu" "F.Mask" "F.Paste")
			(net "GND")
		)
		(pad "98" smd rect
			(at -2.050034 24.224996 90)
			(size 0.519938 1.4986)
			(layers "F.Cu" "F.Mask" "F.Paste")
			(net "M_C_CPU0_SB_CB<1>")
		)
		(pad "99" smd rect
			(at -2.050034 25.07488 90)
			(size 0.519938 1.4986)
			(layers "F.Cu" "F.Mask" "F.Paste")
			(net "GND")
		)
		(pad "100" smd rect
			(at -2.050034 25.925018 90)
			(size 0.519938 1.4986)
			(layers "F.Cu" "F.Mask" "F.Paste")
			(net "M_C_CPU0_SB_DQ<0>")
		)
		(pad "101" smd rect
			(at -2.050034 26.774902 90)
			(size 0.519938 1.4986)
			(layers "F.Cu" "F.Mask" "F.Paste")
			(net "GND")
		)
		(pad "102" smd rect
			(at -2.050034 27.62504 90)
			(size 0.519938 1.4986)
			(layers "F.Cu" "F.Mask" "F.Paste")
			(net "M_C_CPU0_SB_DQ<1>")
		)
		(pad "103" smd rect
			(at -2.050034 28.474924 90)
			(size 0.519938 1.4986)
			(layers "F.Cu" "F.Mask" "F.Paste")
			(net "GND")
		)
		(pad "104" smd rect
			(at -2.050034 29.325062 90)
			(size 0.519938 1.4986)
			(layers "F.Cu" "F.Mask" "F.Paste")
			(net "M_C_CPU0_SB_DQS_DP<0>")
		)
		(pad "105" smd rect
			(at -2.050034 30.174946 90)
			(size 0.519938 1.4986)
			(layers "F.Cu" "F.Mask" "F.Paste")
			(net "M_C_CPU0_SB_DQS_DN<0>")
		)
		(pad "106" smd rect
			(at -2.050034 31.025084 90)
			(size 0.519938 1.4986)
			(layers "F.Cu" "F.Mask" "F.Paste")
			(net "GND")
		)
		(pad "107" smd rect
			(at -2.050034 31.874968 90)
			(size 0.519938 1.4986)
			(layers "F.Cu" "F.Mask" "F.Paste")
			(net "M_C_CPU0_SB_DQ<4>")
		)
		(pad "108" smd rect
			(at -2.050034 32.725106 90)
			(size 0.519938 1.4986)
			(layers "F.Cu" "F.Mask" "F.Paste")
			(net "GND")
		)
		(pad "109" smd rect
			(at -2.050034 33.57499 90)
			(size 0.519938 1.4986)
			(layers "F.Cu" "F.Mask" "F.Paste")
			(net "M_C_CPU0_SB_DQ<5>")
		)
		(pad "110" smd rect
			(at -2.050034 34.425128 90)
			(size 0.519938 1.4986)
			(layers "F.Cu" "F.Mask" "F.Paste")
			(net "GND")
		)
		(pad "111" smd rect
			(at -2.050034 35.275012 90)
			(size 0.519938 1.4986)
			(layers "F.Cu" "F.Mask" "F.Paste")
			(net "M_C_CPU0_SB_DQ<8>")
		)
		(pad "112" smd rect
			(at -2.050034 36.124896 90)
			(size 0.519938 1.4986)
			(layers "F.Cu" "F.Mask" "F.Paste")
			(net "GND")
		)
		(pad "113" smd rect
			(at -2.050034 36.975034 90)
			(size 0.519938 1.4986)
			(layers "F.Cu" "F.Mask" "F.Paste")
			(net "M_C_CPU0_SB_DQ<9>")
		)
	)
)
